FILE_TYPE=LIBRARY_PARTS;
primitive 'MOSFET_PCH_GDS';
  pin
    'D':
      PIN_NUMBER='(D)';
      BIDIRECTIONAL='TRUE';
      INPUT_LOAD='(-0.01,0.01)';
      OUTPUT_LOAD='(1.0,-1.0)';
    'G':
      PIN_NUMBER='(G)';
      INPUT_LOAD='(-0.01,0.01)';
    'S':
      PIN_NUMBER='(S)';
      BIDIRECTIONAL='TRUE';
      INPUT_LOAD='(-0.01,0.01)';
      OUTPUT_LOAD='(1.0,-1.0)';
  end_pin;
  body
    PART_NAME='MOSFET_PCH_GDS';
    BODY_NAME='MOSFET_PCH_GDS';
    PHYS_DES_PREFIX='Q';
    CLASS='DISCRETE';
  end_body;
end_primitive;

END.
